#ISCELL
  mstr_misc dns *
  *
#ISCELL
  pure_quanta quanta_title_block_c *
  *
#ISCELL
  pure_quanta_power vcc_core *
  page420_i10
#ISCELL
  pure_quanta_power universal_gnd *
  page420_i11
#ISCELL
  pure_quanta_power universal_gnd *
  page420_i12
#CELL
  pure_quanta q_res *
  page420_i13
#CELL
  pure_quanta q_res *
  page420_i14
#ISCELL
  pure_quanta_power universal_gnd *
  page420_i15
#ISCELL
  pure_quanta_power universal_gnd *
  page420_i16
#CELL
  pure_quanta pt5161lrs *
  page420_i17
#CELL
  pure_quanta q_res *
  page420_i18
#CELL
  pure_quanta q_res *
  page420_i19
#ISCELL
  pure_quanta_power p1v0 *
  page420_i2
#ISCELL
  pure_quanta_power p1v0 *
  page420_i3
#ISCELL
  pure_quanta_power universal_gnd *
  page420_i4
#CELL
  pure_quanta pt5161lrs *
  page420_i6
#ISCELL
  pure_quanta_power p1v0 *
  page420_i7
#ISCELL
  pure_quanta_power p1v0 *
  page420_i8
#ISCELL
  pure_quanta_power vcc_core *
  page420_i9
